# S9S_MB_2U (Grand Teton) — schematic netlist excerpt (pin names and nets, part order shuffled) for the footprints in the layout excerpt that follows; sources: Cadence DE-HDL packaged netlist, KiCad conversion of 03242023_DA0F0TMBIJ0_F0T_Motherboard_J_brd_V01_OCP.brd

PR4003  Q_RES  10 1% EMPTY  pkg 0402LF  page 242 : A = P12V_AUX ; B = P12V_SCM_VCC
C1227  Q_CAP  100NF 50V 10% X7R  pkg C0402  page 260 : A = P5V ; B = GND

(kicad_pcb
	(version 20260206)
	(generator "pcbnew")
	(generator_version "10.0")
	(general
		(thickness 1.6)
		(legacy_teardrops no)
	)
	(paper "A4")
	(title_block
		(title "03242023_DA0F0TMBIJ0_F0T_Motherboard_J_brd_V01_OCP.brd")
		(comment 1 "Grand Teton / footprints 861-862 of 6105")
	)
	(layers
		(0 "F.Cu" signal "TOP")
		(4 "In1.Cu" signal "GND")
		(6 "In2.Cu" signal "IN1")
		(8 "In3.Cu" signal "GND1")
		(10 "In4.Cu" signal "IN2")
		(12 "In5.Cu" signal "GND2")
		(14 "In6.Cu" signal "IN3")
		(16 "In7.Cu" signal "GND3")
		(18 "In8.Cu" signal "VCC")
		(20 "In9.Cu" signal "VCC1")
		(22 "In10.Cu" signal "GND4")
		(24 "In11.Cu" signal "IN4")
		(26 "In12.Cu" signal "GND5")
		(28 "In13.Cu" signal "IN5")
		(30 "In14.Cu" signal "GND6")
		(32 "In15.Cu" signal "IN6")
		(34 "In16.Cu" signal "GND7")
		(2 "B.Cu" signal "BOTTOM")
		(9 "F.Adhes" user "F.Adhesive")
		(11 "B.Adhes" user "B.Adhesive")
		(13 "F.Paste" user "Package Geometry/Pastemask Top")
		(15 "B.Paste" user "Package Geometry/Pastemask Bottom")
		(5 "F.SilkS" user "Ref Des/Silkscreen Top")
		(7 "B.SilkS" user "Ref Des/Silkscreen Bottom")
		(1 "F.Mask" user "Board Geometry/Soldermask Top")
		(3 "B.Mask" user "Board Geometry/Soldermask Bottom")
		(17 "Dwgs.User" user "User.Drawings")
		(19 "Cmts.User" user "User.Comments")
		(21 "Eco1.User" user "User.Eco1")
		(23 "Eco2.User" user "User.Eco2")
		(25 "Edge.Cuts" user "Board Geometry/Outline")
		(27 "Margin" user)
		(31 "F.CrtYd" user "Package Geometry/Place Bound Top")
		(29 "B.CrtYd" user "Package Geometry/Place Bound Bottom")
		(35 "F.Fab" user "Ref Des/Assembly Top")
		(33 "B.Fab" user "Ref Des/Assembly Bottom")
	)
	(footprint ""
		(layer "F.Cu")
		(at 442.70549 -368.767614)
		(property "Reference" "C1227"
			(at 0 0 0)
			(layer "F.SilkS")
			(hide yes)
			(effects
				(font
					(size 1.27 1.27)
				)
			)
		)
		(property "Value" ""
			(at 0 0 0)
			(layer "F.Fab")
			(effects
				(font
					(size 1.27 1.27)
				)
			)
		)
		(duplicate_pad_numbers_are_jumpers no)
		(fp_line
			(start -0.7874 -0.4064)
			(end 0.7874 -0.4064)
			(stroke
				(width 0.1524)
				(type default)
			)
			(layer "F.SilkS")
		)
		(fp_line
			(start -0.7874 0.4064)
			(end -0.7874 -0.4064)
			(stroke
				(width 0.1524)
				(type default)
			)
			(layer "F.SilkS")
		)
		(fp_line
			(start 0.7874 -0.4064)
			(end 0.7874 0.4064)
			(stroke
				(width 0.1524)
				(type default)
			)
			(layer "F.SilkS")
		)
		(fp_line
			(start 0.7874 0.4064)
			(end -0.7874 0.4064)
			(stroke
				(width 0.1524)
				(type default)
			)
			(layer "F.SilkS")
		)
		(fp_line
			(start -0.67945 -0.305054)
			(end -0.12065 -0.305054)
			(stroke
				(width 0.1)
				(type default)
			)
			(layer "F.Fab")
		)
		(fp_line
			(start -0.67945 0.3048)
			(end -0.67945 -0.305054)
			(stroke
				(width 0.1)
				(type default)
			)
			(layer "F.Fab")
		)
		(fp_line
			(start -0.12065 -0.305054)
			(end -0.12065 -0.2794)
			(stroke
				(width 0.1)
				(type default)
			)
			(layer "F.Fab")
		)
		(fp_line
			(start -0.12065 -0.2794)
			(end 0.12065 -0.2794)
			(stroke
				(width 0.1)
				(type default)
			)
			(layer "F.Fab")
		)
		(fp_line
			(start -0.12065 0.2794)
			(end -0.12065 0.3048)
			(stroke
				(width 0.1)
				(type default)
			)
			(layer "F.Fab")
		)
		(fp_line
			(start -0.12065 0.3048)
			(end -0.67945 0.3048)
			(stroke
				(width 0.1)
				(type default)
			)
			(layer "F.Fab")
		)
		(fp_line
			(start 0.120396 0.2794)
			(end -0.12065 0.2794)
			(stroke
				(width 0.1)
				(type default)
			)
			(layer "F.Fab")
		)
		(fp_line
			(start 0.120396 0.3048)
			(end 0.120396 0.2794)
			(stroke
				(width 0.1)
				(type default)
			)
			(layer "F.Fab")
		)
		(fp_line
			(start 0.12065 -0.3048)
			(end 0.67945 -0.3048)
			(stroke
				(width 0.1)
				(type default)
			)
			(layer "F.Fab")
		)
		(fp_line
			(start 0.12065 -0.2794)
			(end 0.12065 -0.3048)
			(stroke
				(width 0.1)
				(type default)
			)
			(layer "F.Fab")
		)
		(fp_line
			(start 0.67945 -0.3048)
			(end 0.67945 0.3048)
			(stroke
				(width 0.1)
				(type default)
			)
			(layer "F.Fab")
		)
		(fp_line
			(start 0.67945 0.3048)
			(end 0.120396 0.3048)
			(stroke
				(width 0.1)
				(type default)
			)
			(layer "F.Fab")
		)
		(pad "1" smd circle
			(at -0.40005 0)
			(size 0 0)
			(layers "F.Cu" "F.Mask" "F.Paste")
			(net "P5V")
		)
		(pad "2" smd circle
			(at 0.40005 0)
			(size 0 0)
			(layers "F.Cu" "F.Mask" "F.Paste")
			(net "GND")
		)
	)
	(footprint ""
		(layer "F.Cu")
		(at 188.28258 -29.758386 -90)
		(property "Reference" "PR4003"
			(at 0 0 270)
			(layer "F.SilkS")
			(hide yes)
			(effects
				(font
					(size 1.27 1.27)
				)
			)
		)
		(property "Value" ""
			(at 0 0 270)
			(layer "F.Fab")
			(effects
				(font
					(size 1.27 1.27)
				)
			)
		)
		(duplicate_pad_numbers_are_jumpers no)
		(fp_line
			(start -0.7874 0.4064)
			(end -0.7874 -0.4064)
			(stroke
				(width 0.1524)
				(type default)
			)
			(layer "F.SilkS")
		)
		(fp_line
			(start 0.7874 0.4064)
			(end -0.7874 0.4064)
			(stroke
				(width 0.1524)
				(type default)
			)
			(layer "F.SilkS")
		)
		(fp_line
			(start -0.7874 -0.4064)
			(end 0.7874 -0.4064)
			(stroke
				(width 0.1524)
				(type default)
			)
			(layer "F.SilkS")
		)
		(fp_line
			(start 0.7874 -0.4064)
			(end 0.7874 0.4064)
			(stroke
				(width 0.1524)
				(type default)
			)
			(layer "F.SilkS")
		)
		(fp_line
			(start -0.67945 0.3048)
			(end -0.67945 -0.305054)
			(stroke
				(width 0.1)
				(type default)
			)
			(layer "F.Fab")
		)
		(fp_line
			(start -0.12065 0.3048)
			(end -0.67945 0.3048)
			(stroke
				(width 0.1)
				(type default)
			)
			(layer "F.Fab")
		)
		(fp_line
			(start 0.120396 0.3048)
			(end 0.120396 0.2794)
			(stroke
				(width 0.1)
				(type default)
			)
			(layer "F.Fab")
		)
		(fp_line
			(start 0.67945 0.3048)
			(end 0.120396 0.3048)
			(stroke
				(width 0.1)
				(type default)
			)
			(layer "F.Fab")
		)
		(fp_line
			(start -0.12065 0.2794)
			(end -0.12065 0.3048)
			(stroke
				(width 0.1)
				(type default)
			)
			(layer "F.Fab")
		)
		(fp_line
			(start 0.120396 0.2794)
			(end -0.12065 0.2794)
			(stroke
				(width 0.1)
				(type default)
			)
			(layer "F.Fab")
		)
		(fp_line
			(start -0.12065 -0.2794)
			(end 0.12065 -0.2794)
			(stroke
				(width 0.1)
				(type default)
			)
			(layer "F.Fab")
		)
		(fp_line
			(start 0.12065 -0.2794)
			(end 0.12065 -0.3048)
			(stroke
				(width 0.1)
				(type default)
			)
			(layer "F.Fab")
		)
		(fp_line
			(start 0.12065 -0.3048)
			(end 0.67945 -0.3048)
			(stroke
				(width 0.1)
				(type default)
			)
			(layer "F.Fab")
		)
		(fp_line
			(start 0.67945 -0.3048)
			(end 0.67945 0.3048)
			(stroke
				(width 0.1)
				(type default)
			)
			(layer "F.Fab")
		)
		(fp_line
			(start -0.67945 -0.305054)
			(end -0.12065 -0.305054)
			(stroke
				(width 0.1)
				(type default)
			)
			(layer "F.Fab")
		)
		(fp_line
			(start -0.12065 -0.305054)
			(end -0.12065 -0.2794)
			(stroke
				(width 0.1)
				(type default)
			)
			(layer "F.Fab")
		)
		(pad "1" smd circle
			(at -0.40005 0 270)
			(size 0 0)
			(layers "F.Cu" "F.Mask" "F.Paste")
			(net "P12V_AUX")
		)
		(pad "2" smd circle
			(at 0.40005 0 270)
			(size 0 0)
			(layers "F.Cu" "F.Mask" "F.Paste")
			(net "P12V_SCM_VCC")
		)
	)
)
